(kicad_pcb
	(version 20241229)
	(generator "pcbnew")
	(generator_version "9.0")
	(general
		(thickness 1.6296)
		(legacy_teardrops no)
	)
	(paper "A3")
	(title_block
		(title "Thunderbolt to 10GbE adapter")
		(date "2026-04-21")
		(rev "1.1.0")
		(company "Antmicro Ltd")
		(comment 1 "www.antmicro.com")
		(comment 9 "footprints 232-235 of 703")
	)
	(layers
		(0 "F.Cu" signal)
		(4 "In1.Cu" signal)
		(6 "In2.Cu" signal)
		(8 "In3.Cu" signal)
		(10 "In4.Cu" signal)
		(12 "In5.Cu" signal)
		(14 "In6.Cu" signal)
		(2 "B.Cu" signal)
		(9 "F.Adhes" user "F.Adhesive")
		(11 "B.Adhes" user "B.Adhesive")
		(13 "F.Paste" user)
		(15 "B.Paste" user)
		(5 "F.SilkS" user "F.Silkscreen")
		(7 "B.SilkS" user "B.Silkscreen")
		(1 "F.Mask" user)
		(3 "B.Mask" user)
		(17 "Dwgs.User" user "User.Drawings")
		(19 "Cmts.User" user "User.Comments")
		(21 "Eco1.User" user "User.Eco1")
		(23 "Eco2.User" user "User.Eco2")
		(25 "Edge.Cuts" user)
		(27 "Margin" user)
		(31 "F.CrtYd" user "F.Courtyard")
		(29 "B.CrtYd" user "B.Courtyard")
		(35 "F.Fab" user)
		(33 "B.Fab" user)
	)
	(footprint "antmicro-footprints:R_0402_1005Metric"
		(layer "F.Cu")
		(at 119.25 67.5 180)
		(descr "Resistor SMD 0402")
		(tags "resistor SMD 0402")
		(property "Reference" "R136"
			(at -3.45 -1.4 180)
			(layer "F.SilkS")
			(effects
				(font
					(size 0.7 0.7)
					(thickness 0.15)
				)
				(justify left bottom)
			)
		)
		(property "Value" "R_10k_0402"
			(at -1.011843 1.772047 180)
			(layer "F.Fab")
			(effects
				(font
					(size 0.7 0.7)
					(thickness 0.15)
				)
				(justify left bottom)
			)
		)
		(property "Datasheet" "https://www.bourns.com/docs/product-datasheets/cr.pdf"
			(at 0 0 180)
			(layer "F.Fab")
			(hide yes)
			(effects
				(font
					(size 1.27 1.27)
					(thickness 0.15)
				)
			)
		)
		(property "Description" "SMD Chip Resistor, 10 kohm, ± 1%, 62.5 mW, 0402 [1005 Metric], Thick Film, General Purpose"
			(at 0 0 180)
			(layer "F.Fab")
			(hide yes)
			(effects
				(font
					(size 1.27 1.27)
					(thickness 0.15)
				)
			)
		)
		(property "MPN" "CR0402-FX-1002GLF"
			(at 0 0 180)
			(unlocked yes)
			(layer "F.Fab")
			(hide yes)
			(effects
				(font
					(size 1 1)
					(thickness 0.15)
				)
			)
		)
		(property "Manufacturer" "Bourns"
			(at 0 0 180)
			(unlocked yes)
			(layer "F.Fab")
			(hide yes)
			(effects
				(font
					(size 1 1)
					(thickness 0.15)
				)
			)
		)
		(property "License" "Apache-2.0"
			(at 0 0 180)
			(unlocked yes)
			(layer "F.Fab")
			(hide yes)
			(effects
				(font
					(size 1 1)
					(thickness 0.15)
				)
			)
		)
		(property "Author" "Antmicro"
			(at 0 0 180)
			(unlocked yes)
			(layer "F.Fab")
			(hide yes)
			(effects
				(font
					(size 1 1)
					(thickness 0.15)
				)
			)
		)
		(property "Val" "10k"
			(at 0 0 180)
			(unlocked yes)
			(layer "F.Fab")
			(hide yes)
			(effects
				(font
					(size 1 1)
					(thickness 0.15)
				)
			)
		)
		(property "Tolerance" "1%"
			(at 0 0 180)
			(unlocked yes)
			(layer "F.Fab")
			(hide yes)
			(effects
				(font
					(size 1 1)
					(thickness 0.15)
				)
			)
		)
		(sheetname "/X710-AT2 RSVD/")
		(sheetfile "x710-at2-rsvd.kicad_sch")
		(attr smd)
		(fp_rect
			(start -0.925 -0.47)
			(end 0.925 0.47)
			(stroke
				(width 0.05)
				(type default)
			)
			(fill no)
			(layer "F.CrtYd")
		)
		(fp_rect
			(start -0.5 -0.25)
			(end 0.5 0.25)
			(stroke
				(width 0.15)
				(type solid)
			)
			(fill no)
			(layer "F.Fab")
		)
		(fp_text user "${REFERENCE}"
			(at -0.95 3.168 180)
			(layer "F.Fab")
			(effects
				(font
					(size 0.7 0.7)
					(thickness 0.15)
				)
				(justify left bottom)
			)
		)
		(fp_text user "Author: Antmicro"
			(at -0.95 4.169 180)
			(layer "F.Fab")
			(effects
				(font
					(size 0.7 0.7)
					(thickness 0.15)
				)
				(justify left bottom)
			)
		)
		(fp_text user "License: Apache-2.0"
			(at -0.95 5.169 180)
			(layer "F.Fab")
			(effects
				(font
					(size 0.7 0.7)
					(thickness 0.15)
				)
				(justify left bottom)
			)
		)
		(pad "1" smd roundrect
			(at -0.48 0 180)
			(size 0.59 0.64)
			(layers "F.Cu" "F.Mask" "F.Paste")
			(roundrect_rratio 0.25)
			(net 23 "GND")
			(pintype "passive")
		)
		(pad "2" smd roundrect
			(at 0.48 0 180)
			(size 0.59 0.64)
			(layers "F.Cu" "F.Mask" "F.Paste")
			(roundrect_rratio 0.25)
			(net 91 "/X710-AT2 RSVD/DEBUG_Y16")
			(pintype "passive")
		)
	)
	(footprint "antmicro-footprints:D_SOD-123"
		(layer "F.Cu")
		(at 127.8 57.2 -90)
		(property "Reference" "D15"
			(at -1.2 2 90)
			(layer "F.SilkS")
			(effects
				(font
					(size 0.7 0.7)
					(thickness 0.15)
				)
				(justify right top)
			)
		)
		(property "Value" "PTVS26VS1UR,115"
			(at 0 1.95 90)
			(layer "F.Fab")
			(effects
				(font
					(size 0.7 0.7)
					(thickness 0.15)
				)
				(justify right top)
			)
		)
		(property "Datasheet" "https://www.mouser.com/datasheet/2/916/PTVSXS1UR_SER-1545507.pdf"
			(at 0 0 90)
			(layer "F.Fab")
			(hide yes)
			(effects
				(font
					(size 1.27 1.27)
					(thickness 0.15)
				)
			)
		)
		(property "Description" "Unidirectional TVS, 8 kV,  SOD-123F, 26 V, 400 W"
			(at 0 0 90)
			(layer "F.Fab")
			(hide yes)
			(effects
				(font
					(size 1.27 1.27)
					(thickness 0.15)
				)
			)
		)
		(property "Author" "Antmicro"
			(at 0 0 270)
			(unlocked yes)
			(layer "F.Fab")
			(hide yes)
			(effects
				(font
					(size 1 1)
					(thickness 0.15)
				)
			)
		)
		(property "License" "Apache-2.0"
			(at 0 0 270)
			(unlocked yes)
			(layer "F.Fab")
			(hide yes)
			(effects
				(font
					(size 1 1)
					(thickness 0.15)
				)
			)
		)
		(property "Manufacturer" "Nexperia"
			(at 0 0 270)
			(unlocked yes)
			(layer "F.Fab")
			(hide yes)
			(effects
				(font
					(size 1 1)
					(thickness 0.15)
				)
			)
		)
		(property "MPN" "PTVS26VS1UR,115"
			(at 0 0 270)
			(unlocked yes)
			(layer "F.Fab")
			(hide yes)
			(effects
				(font
					(size 1 1)
					(thickness 0.15)
				)
			)
		)
		(sheetname "/Power input/")
		(sheetfile "power_input.kicad_sch")
		(attr smd)
		(fp_line
			(start 1.1 0.8875)
			(end 1.45 0.8875)
			(stroke
				(width 0.15)
				(type solid)
			)
			(layer "F.SilkS")
		)
		(fp_line
			(start -1.45 0.8625)
			(end -1.45 0.5875)
			(stroke
				(width 0.15)
				(type solid)
			)
			(layer "F.SilkS")
		)
		(fp_line
			(start -1.1 0.8625)
			(end -1.45 0.8625)
			(stroke
				(width 0.15)
				(type solid)
			)
			(layer "F.SilkS")
		)
		(fp_line
			(start 1.45 0.6125)
			(end 1.45 0.8875)
			(stroke
				(width 0.15)
				(type solid)
			)
			(layer "F.SilkS")
		)
		(fp_line
			(start -0.925 -0.5)
			(end -0.925 0.5)
			(stroke
				(width 0.15)
				(type solid)
			)
			(layer "F.SilkS")
		)
		(fp_line
			(start -1.45 -0.6)
			(end -1.45 -0.875)
			(stroke
				(width 0.15)
				(type solid)
			)
			(layer "F.SilkS")
		)
		(fp_line
			(start -1.1 -0.875)
			(end -1.45 -0.875)
			(stroke
				(width 0.15)
				(type solid)
			)
			(layer "F.SilkS")
		)
		(fp_line
			(start 1.1 -0.875)
			(end 1.45 -0.875)
			(stroke
				(width 0.15)
				(type solid)
			)
			(layer "F.SilkS")
		)
		(fp_line
			(start 1.45 -0.875)
			(end 1.45 -0.6)
			(stroke
				(width 0.15)
				(type solid)
			)
			(layer "F.SilkS")
		)
		(fp_rect
			(start -2.275 -1.05)
			(end 2.275 1.05)
			(stroke
				(width 0.05)
				(type solid)
			)
			(fill no)
			(layer "F.CrtYd")
		)
		(fp_line
			(start -1.325 0.848)
			(end 1.324 0.848)
			(stroke
				(width 0.15)
				(type solid)
			)
			(layer "F.Fab")
		)
		(fp_line
			(start -1.325 -0.85)
			(end -1.325 0.848)
			(stroke
				(width 0.15)
				(type solid)
			)
			(layer "F.Fab")
		)
		(fp_line
			(start -1.325 -0.85)
			(end 1.324 -0.85)
			(stroke
				(width 0.15)
				(type solid)
			)
			(layer "F.Fab")
		)
		(fp_line
			(start 1.324 -0.85)
			(end 1.324 0.848)
			(stroke
				(width 0.15)
				(type solid)
			)
			(layer "F.Fab")
		)
		(fp_text user "Author: Antmicro"
			(at -2.36 4.6 90)
			(layer "F.Fab")
			(effects
				(font
					(size 0.7 0.7)
					(thickness 0.15)
				)
				(justify right top)
			)
		)
		(fp_text user "${REFERENCE}"
			(at -2.36 3.3 90)
			(layer "F.Fab")
			(effects
				(font
					(size 0.7 0.7)
					(thickness 0.15)
				)
				(justify right top)
			)
		)
		(fp_text user "License: Apache-2.0"
			(at -2.36 5.85 90)
			(layer "F.Fab")
			(effects
				(font
					(size 0.7 0.7)
					(thickness 0.15)
				)
				(justify right top)
			)
		)
		(pad "1" smd roundrect
			(at -1.625 -0.001 270)
			(size 0.9 0.95)
			(layers "F.Cu" "F.Mask" "F.Paste")
			(roundrect_rratio 0.15)
			(net 412 "Net-(D15-C)")
			(pinfunction "C")
			(pintype "passive")
		)
		(pad "2" smd roundrect
			(at 1.625 -0.001 270)
			(size 0.9 0.95)
			(layers "F.Cu" "F.Mask" "F.Paste")
			(roundrect_rratio 0.15)
			(net 23 "GND")
			(pinfunction "A")
			(pintype "passive")
		)
	)
	(footprint "antmicro-footprints:Fiducial_1mm_Mask2mm"
		(layer "F.Cu")
		(at 175 47.5)
		(descr "Circular Fiducial, 1mm bare copper, 3mm soldermask opening")
		(tags "fiducial")
		(property "Reference" "FD3"
			(at -3.6 0.5 0)
			(layer "F.SilkS")
			(effects
				(font
					(size 0.7 0.7)
					(thickness 0.15)
				)
				(justify left bottom)
			)
		)
		(property "Value" "Fiducial_1mm_Mask2mm"
			(at 0 2.2 0)
			(layer "F.Fab")
			(effects
				(font
					(size 0.7 0.7)
					(thickness 0.15)
				)
				(justify left bottom)
			)
		)
		(property "Description" "Fiducial mask"
			(at 0 0 0)
			(layer "F.Fab")
			(hide yes)
			(effects
				(font
					(size 1.27 1.27)
					(thickness 0.15)
				)
			)
		)
		(property "Author" "Antmicro"
			(at 0 0 0)
			(unlocked yes)
			(layer "F.Fab")
			(hide yes)
			(effects
				(font
					(size 1 1)
					(thickness 0.15)
				)
			)
		)
		(property "License" "Apache-2.0"
			(at 0 0 0)
			(unlocked yes)
			(layer "F.Fab")
			(hide yes)
			(effects
				(font
					(size 1 1)
					(thickness 0.15)
				)
			)
		)
		(sheetname "/")
		(sheetfile "thunderbolt-to-10gbe-adapter.kicad_sch")
		(attr exclude_from_pos_files exclude_from_bom)
		(fp_circle
			(center 0 0)
			(end 1.24 0)
			(stroke
				(width 0.05)
				(type solid)
			)
			(fill no)
			(layer "F.CrtYd")
		)
		(fp_circle
			(center 0 0)
			(end 0.999 0)
			(stroke
				(width 0.15)
				(type solid)
			)
			(fill no)
			(layer "F.Fab")
		)
		(fp_text user "${REFERENCE}"
			(at -1.25 4.603 0)
			(layer "F.Fab")
			(effects
				(font
					(size 0.7 0.7)
					(thickness 0.15)
				)
				(justify left bottom)
			)
		)
		(fp_text user "License: Apache-2.0"
			(at -1.25 7.003 0)
			(layer "F.Fab")
			(effects
				(font
					(size 0.7 0.7)
					(thickness 0.15)
				)
				(justify left bottom)
			)
		)
		(fp_text user "Author: Antmicro"
			(at -1.25 5.803 0)
			(layer "F.Fab")
			(effects
				(font
					(size 0.7 0.7)
					(thickness 0.15)
				)
				(justify left bottom)
			)
		)
		(pad "" smd circle
			(at 0 0)
			(size 1 1)
			(layers "F.Cu" "F.Mask")
			(solder_mask_margin 0.5)
			(clearance 0.5)
		)
	)
	(footprint "antmicro-footprints:C_0603_1608Metric"
		(layer "F.Cu")
		(at 154.705001 94.024999 180)
		(descr "Capacitor SMD 0603")
		(tags "capacitor 0603")
		(property "Reference" "C173"
			(at -23.294999 -19.625001 180)
			(layer "F.SilkS")
			(effects
				(font
					(size 0.7 0.7)
					(thickness 0.15)
				)
			)
		)
		(property "Value" "C_10u_10V_X7R_0603"
			(at -1.42757 1.770288 180)
			(layer "F.Fab")
			(effects
				(font
					(size 0.7 0.7)
					(thickness 0.15)
				)
				(justify left bottom)
			)
		)
		(property "Datasheet" "https://www.murata.com/products/productdetail?partno=GRM188Z71A106KA73%23"
			(at 0 0 180)
			(layer "F.Fab")
			(hide yes)
			(effects
				(font
					(size 1.27 1.27)
					(thickness 0.15)
				)
			)
		)
		(property "Description" "SMD Multilayer Ceramic Capacitor,  10µF, 10V, 0603, ±10%, X7R"
			(at 0 0 180)
			(layer "F.Fab")
			(hide yes)
			(effects
				(font
					(size 1.27 1.27)
					(thickness 0.15)
				)
			)
		)
		(property "MPN" "GRM188Z71A106KA73D"
			(at 0 0 180)
			(unlocked yes)
			(layer "F.Fab")
			(hide yes)
			(effects
				(font
					(size 1 1)
					(thickness 0.15)
				)
			)
		)
		(property "Val" "10u"
			(at 0 0 180)
			(unlocked yes)
			(layer "F.Fab")
			(hide yes)
			(effects
				(font
					(size 1 1)
					(thickness 0.15)
				)
			)
		)
		(property "Voltage" "10V"
			(at 0 0 180)
			(unlocked yes)
			(layer "F.Fab")
			(hide yes)
			(effects
				(font
					(size 1 1)
					(thickness 0.15)
				)
			)
		)
		(property "Dielectric" "X7R"
			(at 0 0 180)
			(unlocked yes)
			(layer "F.Fab")
			(hide yes)
			(effects
				(font
					(size 1 1)
					(thickness 0.15)
				)
			)
		)
		(property "Manufacturer" "Murata"
			(at 0 0 180)
			(unlocked yes)
			(layer "F.Fab")
			(hide yes)
			(effects
				(font
					(size 1 1)
					(thickness 0.15)
				)
			)
		)
		(property "License" "Apache-2.0"
			(at 0 0 180)
			(unlocked yes)
			(layer "F.Fab")
			(hide yes)
			(effects
				(font
					(size 1 1)
					(thickness 0.15)
				)
			)
		)
		(property "Author" "Antmicro"
			(at 0 0 180)
			(unlocked yes)
			(layer "F.Fab")
			(hide yes)
			(effects
				(font
					(size 1 1)
					(thickness 0.15)
				)
			)
		)
		(sheetname "/X710-AT2 power/")
		(sheetfile "x710-at2-power.kicad_sch")
		(attr smd)
		(fp_line
			(start -0.15 0.4)
			(end 0.15 0.4)
			(stroke
				(width 0.15)
				(type solid)
			)
			(layer "F.SilkS")
		)
		(fp_line
			(start -0.15 -0.4)
			(end 0.15 -0.4)
			(stroke
				(width 0.15)
				(type solid)
			)
			(layer "F.SilkS")
		)
		(fp_rect
			(start -1.25 -0.65)
			(end 1.25 0.65)
			(stroke
				(width 0.05)
				(type solid)
			)
			(fill no)
			(layer "F.CrtYd")
		)
		(fp_rect
			(start -0.8 -0.4)
			(end 0.8 0.4)
			(stroke
				(width 0.15)
				(type solid)
			)
			(fill no)
			(layer "F.Fab")
		)
		(fp_text user "Author: Antmicro"
			(at -1.682 4.894 180)
			(layer "F.Fab")
			(effects
				(font
					(size 0.7 0.7)
					(thickness 0.15)
				)
				(justify left bottom)
			)
		)
		(fp_text user "${REFERENCE}"
			(at -1.682 3.895 180)
			(layer "F.Fab")
			(effects
				(font
					(size 0.7 0.7)
					(thickness 0.15)
				)
				(justify left bottom)
			)
		)
		(fp_text user "License: Apache-2.0"
			(at -1.682 5.895 180)
			(layer "F.Fab")
			(effects
				(font
					(size 0.7 0.7)
					(thickness 0.15)
				)
				(justify left bottom)
			)
		)
		(pad "1" smd roundrect
			(at -0.7 0 180)
			(size 0.8 1)
			(layers "F.Cu" "F.Mask" "F.Paste")
			(roundrect_rratio 0.2)
			(net 23 "GND")
			(pintype "passive")
		)
		(pad "2" smd roundrect
			(at 0.7 0 180)
			(size 0.8 1)
			(layers "F.Cu" "F.Mask" "F.Paste")
			(roundrect_rratio 0.2)
			(net 21 "XFI_PVDD")
			(pintype "passive")
		)
	)
)
